FILE_TYPE=LIBRARY_PARTS;
primitive 'IML3112Y2B000NCG8';
  pin
    'HSDA':
      PIN_NUMBER='(2)';
      BIDIRECTIONAL='TRUE';
      INPUT_LOAD='(-0.01,0.01)';
      OUTPUT_LOAD='(1.0,-1.0)';
    'VDD':
      PIN_NUMBER='(5)';
      PINUSE='POWER';
      NO_LOAD_CHECK='Both';
      NO_IO_CHECK='Both';
      NO_ASSERT_CHECK='TRUE';
      NO_DIR_CHECK='TRUE';
      ALLOW_CONNECT='TRUE';
    'LSCL_1':
      PIN_NUMBER='(6)';
      OUTPUT_LOAD='(1.0,-1.0)';
    'VIO':
      PIN_NUMBER='(7)';
      PINUSE='POWER';
      NO_LOAD_CHECK='Both';
      NO_IO_CHECK='Both';
      NO_ASSERT_CHECK='TRUE';
      NO_DIR_CHECK='TRUE';
      ALLOW_CONNECT='TRUE';
    'LSDA_0':
      PIN_NUMBER='(1)';
      BIDIRECTIONAL='TRUE';
      INPUT_LOAD='(-0.01,0.01)';
      OUTPUT_LOAD='(1.0,-1.0)';
    'LSCL_0':
      PIN_NUMBER='(4)';
      OUTPUT_LOAD='(1.0,-1.0)';
    'HSCL':
      PIN_NUMBER='(3)';
      INPUT_LOAD='(-0.01,0.01)';
    'LSDA_1||HSA':
      PIN_NUMBER='(8)';
      BIDIRECTIONAL='TRUE';
      INPUT_LOAD='(-0.01,0.01)';
      OUTPUT_LOAD='(1.0,-1.0)';
    'TH_GND':
      PIN_NUMBER='(9)';
      PINUSE='POWER';
      NO_LOAD_CHECK='Both';
      NO_IO_CHECK='Both';
      NO_ASSERT_CHECK='TRUE';
      NO_DIR_CHECK='TRUE';
      ALLOW_CONNECT='TRUE';
  end_pin;
  body
    PART_NAME='IML3112Y2B000NCG8';
    BODY_NAME='IML3112Y2B000NCG8';
    PHYS_DES_PREFIX='U';
    CLASS='IC';
  end_body;
end_primitive;

END.
